(kicad_pcb
	(version 20260206)
	(generator "pcbnew")
	(generator_version "10.0")
	(general
		(thickness 1.6)
		(legacy_teardrops no)
	)
	(paper "A4")
	(title_block
		(title "03242023_DA0F0TMBIJ0_F0T_Motherboard_J_brd_V01_OCP.brd")
		(comment 1 "Grand Teton / footprints 1077-1082 of 6105")
	)
	(layers
		(0 "F.Cu" signal "TOP")
		(4 "In1.Cu" signal "GND")
		(6 "In2.Cu" signal "IN1")
		(8 "In3.Cu" signal "GND1")
		(10 "In4.Cu" signal "IN2")
		(12 "In5.Cu" signal "GND2")
		(14 "In6.Cu" signal "IN3")
		(16 "In7.Cu" signal "GND3")
		(18 "In8.Cu" signal "VCC")
		(20 "In9.Cu" signal "VCC1")
		(22 "In10.Cu" signal "GND4")
		(24 "In11.Cu" signal "IN4")
		(26 "In12.Cu" signal "GND5")
		(28 "In13.Cu" signal "IN5")
		(30 "In14.Cu" signal "GND6")
		(32 "In15.Cu" signal "IN6")
		(34 "In16.Cu" signal "GND7")
		(2 "B.Cu" signal "BOTTOM")
		(9 "F.Adhes" user "F.Adhesive")
		(11 "B.Adhes" user "B.Adhesive")
		(13 "F.Paste" user "Package Geometry/Pastemask Top")
		(15 "B.Paste" user "Package Geometry/Pastemask Bottom")
		(5 "F.SilkS" user "Ref Des/Silkscreen Top")
		(7 "B.SilkS" user "Ref Des/Silkscreen Bottom")
		(1 "F.Mask" user "Board Geometry/Soldermask Top")
		(3 "B.Mask" user "Board Geometry/Soldermask Bottom")
		(17 "Dwgs.User" user "User.Drawings")
		(19 "Cmts.User" user "User.Comments")
		(21 "Eco1.User" user "User.Eco1")
		(23 "Eco2.User" user "User.Eco2")
		(25 "Edge.Cuts" user "Board Geometry/Outline")
		(27 "Margin" user)
		(31 "F.CrtYd" user "Package Geometry/Place Bound Top")
		(29 "B.CrtYd" user "Package Geometry/Place Bound Bottom")
		(35 "F.Fab" user "Ref Des/Assembly Top")
		(33 "B.Fab" user "Ref Des/Assembly Bottom")
	)
	(footprint ""
		(layer "F.Cu")
		(at 20.11426 -163.719256)
		(property "Reference" "R2593"
			(at 0 0 0)
			(layer "F.SilkS")
			(hide yes)
			(effects
				(font
					(size 1.27 1.27)
				)
			)
		)
		(property "Value" ""
			(at 0 0 0)
			(layer "F.Fab")
			(effects
				(font
					(size 1.27 1.27)
				)
			)
		)
		(duplicate_pad_numbers_are_jumpers no)
		(fp_line
			(start -0.7874 -0.4064)
			(end 0.7874 -0.4064)
			(stroke
				(width 0.1524)
				(type default)
			)
			(layer "F.SilkS")
		)
		(fp_line
			(start -0.7874 0.4064)
			(end -0.7874 -0.4064)
			(stroke
				(width 0.1524)
				(type default)
			)
			(layer "F.SilkS")
		)
		(fp_line
			(start 0.7874 -0.4064)
			(end 0.7874 0.4064)
			(stroke
				(width 0.1524)
				(type default)
			)
			(layer "F.SilkS")
		)
		(fp_line
			(start 0.7874 0.4064)
			(end -0.7874 0.4064)
			(stroke
				(width 0.1524)
				(type default)
			)
			(layer "F.SilkS")
		)
		(fp_line
			(start -0.67945 -0.305054)
			(end -0.12065 -0.305054)
			(stroke
				(width 0.1)
				(type default)
			)
			(layer "F.Fab")
		)
		(fp_line
			(start -0.67945 0.3048)
			(end -0.67945 -0.305054)
			(stroke
				(width 0.1)
				(type default)
			)
			(layer "F.Fab")
		)
		(fp_line
			(start -0.12065 -0.305054)
			(end -0.12065 -0.2794)
			(stroke
				(width 0.1)
				(type default)
			)
			(layer "F.Fab")
		)
		(fp_line
			(start -0.12065 -0.2794)
			(end 0.12065 -0.2794)
			(stroke
				(width 0.1)
				(type default)
			)
			(layer "F.Fab")
		)
		(fp_line
			(start -0.12065 0.2794)
			(end -0.12065 0.3048)
			(stroke
				(width 0.1)
				(type default)
			)
			(layer "F.Fab")
		)
		(fp_line
			(start -0.12065 0.3048)
			(end -0.67945 0.3048)
			(stroke
				(width 0.1)
				(type default)
			)
			(layer "F.Fab")
		)
		(fp_line
			(start 0.120396 0.2794)
			(end -0.12065 0.2794)
			(stroke
				(width 0.1)
				(type default)
			)
			(layer "F.Fab")
		)
		(fp_line
			(start 0.120396 0.3048)
			(end 0.120396 0.2794)
			(stroke
				(width 0.1)
				(type default)
			)
			(layer "F.Fab")
		)
		(fp_line
			(start 0.12065 -0.3048)
			(end 0.67945 -0.3048)
			(stroke
				(width 0.1)
				(type default)
			)
			(layer "F.Fab")
		)
		(fp_line
			(start 0.12065 -0.2794)
			(end 0.12065 -0.3048)
			(stroke
				(width 0.1)
				(type default)
			)
			(layer "F.Fab")
		)
		(fp_line
			(start 0.67945 -0.3048)
			(end 0.67945 0.3048)
			(stroke
				(width 0.1)
				(type default)
			)
			(layer "F.Fab")
		)
		(fp_line
			(start 0.67945 0.3048)
			(end 0.120396 0.3048)
			(stroke
				(width 0.1)
				(type default)
			)
			(layer "F.Fab")
		)
		(pad "1" smd circle
			(at -0.40005 0)
			(size 0 0)
			(layers "F.Cu" "F.Mask" "F.Paste")
			(net "PVNN_TERM_CPU1")
		)
		(pad "2" smd circle
			(at 0.40005 0)
			(size 0 0)
			(layers "F.Cu" "F.Mask" "F.Paste")
			(net "SVID_DIO1_CPU1_R")
		)
	)
	(footprint ""
		(layer "F.Cu")
		(at 312.443622 -41.519348 180)
		(property "Reference" "R1581"
			(at 0 0 180)
			(layer "F.SilkS")
			(hide yes)
			(effects
				(font
					(size 1.27 1.27)
				)
			)
		)
		(property "Value" ""
			(at 0 0 180)
			(layer "F.Fab")
			(effects
				(font
					(size 1.27 1.27)
				)
			)
		)
		(duplicate_pad_numbers_are_jumpers no)
		(fp_line
			(start 0.7874 0.4064)
			(end -0.7874 0.4064)
			(stroke
				(width 0.1524)
				(type default)
			)
			(layer "F.SilkS")
		)
		(fp_line
			(start 0.7874 -0.4064)
			(end 0.7874 0.4064)
			(stroke
				(width 0.1524)
				(type default)
			)
			(layer "F.SilkS")
		)
		(fp_line
			(start -0.7874 0.4064)
			(end -0.7874 -0.4064)
			(stroke
				(width 0.1524)
				(type default)
			)
			(layer "F.SilkS")
		)
		(fp_line
			(start -0.7874 -0.4064)
			(end 0.7874 -0.4064)
			(stroke
				(width 0.1524)
				(type default)
			)
			(layer "F.SilkS")
		)
		(fp_line
			(start 0.67945 0.3048)
			(end 0.120396 0.3048)
			(stroke
				(width 0.1)
				(type default)
			)
			(layer "F.Fab")
		)
		(fp_line
			(start 0.67945 -0.3048)
			(end 0.67945 0.3048)
			(stroke
				(width 0.1)
				(type default)
			)
			(layer "F.Fab")
		)
		(fp_line
			(start 0.12065 -0.2794)
			(end 0.12065 -0.3048)
			(stroke
				(width 0.1)
				(type default)
			)
			(layer "F.Fab")
		)
		(fp_line
			(start 0.12065 -0.3048)
			(end 0.67945 -0.3048)
			(stroke
				(width 0.1)
				(type default)
			)
			(layer "F.Fab")
		)
		(fp_line
			(start 0.120396 0.3048)
			(end 0.120396 0.2794)
			(stroke
				(width 0.1)
				(type default)
			)
			(layer "F.Fab")
		)
		(fp_line
			(start 0.120396 0.2794)
			(end -0.12065 0.2794)
			(stroke
				(width 0.1)
				(type default)
			)
			(layer "F.Fab")
		)
		(fp_line
			(start -0.12065 0.3048)
			(end -0.67945 0.3048)
			(stroke
				(width 0.1)
				(type default)
			)
			(layer "F.Fab")
		)
		(fp_line
			(start -0.12065 0.2794)
			(end -0.12065 0.3048)
			(stroke
				(width 0.1)
				(type default)
			)
			(layer "F.Fab")
		)
		(fp_line
			(start -0.12065 -0.2794)
			(end 0.12065 -0.2794)
			(stroke
				(width 0.1)
				(type default)
			)
			(layer "F.Fab")
		)
		(fp_line
			(start -0.12065 -0.305054)
			(end -0.12065 -0.2794)
			(stroke
				(width 0.1)
				(type default)
			)
			(layer "F.Fab")
		)
		(fp_line
			(start -0.67945 0.3048)
			(end -0.67945 -0.305054)
			(stroke
				(width 0.1)
				(type default)
			)
			(layer "F.Fab")
		)
		(fp_line
			(start -0.67945 -0.305054)
			(end -0.12065 -0.305054)
			(stroke
				(width 0.1)
				(type default)
			)
			(layer "F.Fab")
		)
		(pad "1" smd circle
			(at -0.40005 0 180)
			(size 0 0)
			(layers "F.Cu" "F.Mask" "F.Paste")
			(net "PU_SMB_PCH_PLD_3V3AUX_SCL")
		)
		(pad "2" smd circle
			(at 0.40005 0 180)
			(size 0 0)
			(layers "F.Cu" "F.Mask" "F.Paste")
			(net "P3V3_AUX")
		)
	)
	(footprint ""
		(layer "F.Cu")
		(at 14.689582 -423.629836 -90)
		(property "Reference" "R2695"
			(at 0 0 270)
			(layer "F.SilkS")
			(hide yes)
			(effects
				(font
					(size 1.27 1.27)
				)
			)
		)
		(property "Value" ""
			(at 0 0 270)
			(layer "F.Fab")
			(effects
				(font
					(size 1.27 1.27)
				)
			)
		)
		(duplicate_pad_numbers_are_jumpers no)
		(fp_line
			(start -0.7874 0.4064)
			(end -0.7874 -0.4064)
			(stroke
				(width 0.1524)
				(type default)
			)
			(layer "F.SilkS")
		)
		(fp_line
			(start 0.7874 0.4064)
			(end -0.7874 0.4064)
			(stroke
				(width 0.1524)
				(type default)
			)
			(layer "F.SilkS")
		)
		(fp_line
			(start -0.7874 -0.4064)
			(end 0.7874 -0.4064)
			(stroke
				(width 0.1524)
				(type default)
			)
			(layer "F.SilkS")
		)
		(fp_line
			(start 0.7874 -0.4064)
			(end 0.7874 0.4064)
			(stroke
				(width 0.1524)
				(type default)
			)
			(layer "F.SilkS")
		)
		(fp_line
			(start -0.67945 0.3048)
			(end -0.67945 -0.305054)
			(stroke
				(width 0.1)
				(type default)
			)
			(layer "F.Fab")
		)
		(fp_line
			(start -0.12065 0.3048)
			(end -0.67945 0.3048)
			(stroke
				(width 0.1)
				(type default)
			)
			(layer "F.Fab")
		)
		(fp_line
			(start 0.120396 0.3048)
			(end 0.120396 0.2794)
			(stroke
				(width 0.1)
				(type default)
			)
			(layer "F.Fab")
		)
		(fp_line
			(start 0.67945 0.3048)
			(end 0.120396 0.3048)
			(stroke
				(width 0.1)
				(type default)
			)
			(layer "F.Fab")
		)
		(fp_line
			(start -0.12065 0.2794)
			(end -0.12065 0.3048)
			(stroke
				(width 0.1)
				(type default)
			)
			(layer "F.Fab")
		)
		(fp_line
			(start 0.120396 0.2794)
			(end -0.12065 0.2794)
			(stroke
				(width 0.1)
				(type default)
			)
			(layer "F.Fab")
		)
		(fp_line
			(start -0.12065 -0.2794)
			(end 0.12065 -0.2794)
			(stroke
				(width 0.1)
				(type default)
			)
			(layer "F.Fab")
		)
		(fp_line
			(start 0.12065 -0.2794)
			(end 0.12065 -0.3048)
			(stroke
				(width 0.1)
				(type default)
			)
			(layer "F.Fab")
		)
		(fp_line
			(start 0.12065 -0.3048)
			(end 0.67945 -0.3048)
			(stroke
				(width 0.1)
				(type default)
			)
			(layer "F.Fab")
		)
		(fp_line
			(start 0.67945 -0.3048)
			(end 0.67945 0.3048)
			(stroke
				(width 0.1)
				(type default)
			)
			(layer "F.Fab")
		)
		(fp_line
			(start -0.67945 -0.305054)
			(end -0.12065 -0.305054)
			(stroke
				(width 0.1)
				(type default)
			)
			(layer "F.Fab")
		)
		(fp_line
			(start -0.12065 -0.305054)
			(end -0.12065 -0.2794)
			(stroke
				(width 0.1)
				(type default)
			)
			(layer "F.Fab")
		)
		(pad "1" smd circle
			(at -0.40005 0 270)
			(size 0 0)
			(layers "F.Cu" "F.Mask" "F.Paste")
			(net "P3V3_AUX")
		)
		(pad "2" smd circle
			(at 0.40005 0 270)
			(size 0 0)
			(layers "F.Cu" "F.Mask" "F.Paste")
			(net "TCA9539_0_ADD0")
		)
	)
	(footprint ""
		(layer "F.Cu")
		(at 97.821242 -414.771586 -90)
		(property "Reference" "R4195"
			(at 0 0 270)
			(layer "F.SilkS")
			(hide yes)
			(effects
				(font
					(size 1.27 1.27)
				)
			)
		)
		(property "Value" ""
			(at 0 0 270)
			(layer "F.Fab")
			(effects
				(font
					(size 1.27 1.27)
				)
			)
		)
		(duplicate_pad_numbers_are_jumpers no)
		(fp_line
			(start -0.7874 0.4064)
			(end -0.7874 -0.4064)
			(stroke
				(width 0.1524)
				(type default)
			)
			(layer "F.SilkS")
		)
		(fp_line
			(start 0.7874 0.4064)
			(end -0.7874 0.4064)
			(stroke
				(width 0.1524)
				(type default)
			)
			(layer "F.SilkS")
		)
		(fp_line
			(start -0.7874 -0.4064)
			(end 0.7874 -0.4064)
			(stroke
				(width 0.1524)
				(type default)
			)
			(layer "F.SilkS")
		)
		(fp_line
			(start 0.7874 -0.4064)
			(end 0.7874 0.4064)
			(stroke
				(width 0.1524)
				(type default)
			)
			(layer "F.SilkS")
		)
		(fp_line
			(start -0.67945 0.3048)
			(end -0.67945 -0.305054)
			(stroke
				(width 0.1)
				(type default)
			)
			(layer "F.Fab")
		)
		(fp_line
			(start -0.12065 0.3048)
			(end -0.67945 0.3048)
			(stroke
				(width 0.1)
				(type default)
			)
			(layer "F.Fab")
		)
		(fp_line
			(start 0.120396 0.3048)
			(end 0.120396 0.2794)
			(stroke
				(width 0.1)
				(type default)
			)
			(layer "F.Fab")
		)
		(fp_line
			(start 0.67945 0.3048)
			(end 0.120396 0.3048)
			(stroke
				(width 0.1)
				(type default)
			)
			(layer "F.Fab")
		)
		(fp_line
			(start -0.12065 0.2794)
			(end -0.12065 0.3048)
			(stroke
				(width 0.1)
				(type default)
			)
			(layer "F.Fab")
		)
		(fp_line
			(start 0.120396 0.2794)
			(end -0.12065 0.2794)
			(stroke
				(width 0.1)
				(type default)
			)
			(layer "F.Fab")
		)
		(fp_line
			(start -0.12065 -0.2794)
			(end 0.12065 -0.2794)
			(stroke
				(width 0.1)
				(type default)
			)
			(layer "F.Fab")
		)
		(fp_line
			(start 0.12065 -0.2794)
			(end 0.12065 -0.3048)
			(stroke
				(width 0.1)
				(type default)
			)
			(layer "F.Fab")
		)
		(fp_line
			(start 0.12065 -0.3048)
			(end 0.67945 -0.3048)
			(stroke
				(width 0.1)
				(type default)
			)
			(layer "F.Fab")
		)
		(fp_line
			(start 0.67945 -0.3048)
			(end 0.67945 0.3048)
			(stroke
				(width 0.1)
				(type default)
			)
			(layer "F.Fab")
		)
		(fp_line
			(start -0.67945 -0.305054)
			(end -0.12065 -0.305054)
			(stroke
				(width 0.1)
				(type default)
			)
			(layer "F.Fab")
		)
		(fp_line
			(start -0.12065 -0.305054)
			(end -0.12065 -0.2794)
			(stroke
				(width 0.1)
				(type default)
			)
			(layer "F.Fab")
		)
		(pad "1" smd circle
			(at -0.40005 0 270)
			(size 0 0)
			(layers "F.Cu" "F.Mask" "F.Paste")
			(net "U272_2_ADD1")
		)
		(pad "2" smd circle
			(at 0.40005 0 270)
			(size 0 0)
			(layers "F.Cu" "F.Mask" "F.Paste")
			(net "GND")
		)
	)
	(footprint ""
		(layer "F.Cu")
		(at 39.827454 -110.587282)
		(property "Reference" "R3861"
			(at 0 0 0)
			(layer "F.SilkS")
			(hide yes)
			(effects
				(font
					(size 1.27 1.27)
				)
			)
		)
		(property "Value" ""
			(at 0 0 0)
			(layer "F.Fab")
			(effects
				(font
					(size 1.27 1.27)
				)
			)
		)
		(duplicate_pad_numbers_are_jumpers no)
		(fp_line
			(start -0.7874 -0.4064)
			(end 0.7874 -0.4064)
			(stroke
				(width 0.1524)
				(type default)
			)
			(layer "F.SilkS")
		)
		(fp_line
			(start -0.7874 0.4064)
			(end -0.7874 -0.4064)
			(stroke
				(width 0.1524)
				(type default)
			)
			(layer "F.SilkS")
		)
		(fp_line
			(start 0.7874 -0.4064)
			(end 0.7874 0.4064)
			(stroke
				(width 0.1524)
				(type default)
			)
			(layer "F.SilkS")
		)
		(fp_line
			(start 0.7874 0.4064)
			(end -0.7874 0.4064)
			(stroke
				(width 0.1524)
				(type default)
			)
			(layer "F.SilkS")
		)
		(fp_line
			(start -0.67945 -0.305054)
			(end -0.12065 -0.305054)
			(stroke
				(width 0.1)
				(type default)
			)
			(layer "F.Fab")
		)
		(fp_line
			(start -0.67945 0.3048)
			(end -0.67945 -0.305054)
			(stroke
				(width 0.1)
				(type default)
			)
			(layer "F.Fab")
		)
		(fp_line
			(start -0.12065 -0.305054)
			(end -0.12065 -0.2794)
			(stroke
				(width 0.1)
				(type default)
			)
			(layer "F.Fab")
		)
		(fp_line
			(start -0.12065 -0.2794)
			(end 0.12065 -0.2794)
			(stroke
				(width 0.1)
				(type default)
			)
			(layer "F.Fab")
		)
		(fp_line
			(start -0.12065 0.2794)
			(end -0.12065 0.3048)
			(stroke
				(width 0.1)
				(type default)
			)
			(layer "F.Fab")
		)
		(fp_line
			(start -0.12065 0.3048)
			(end -0.67945 0.3048)
			(stroke
				(width 0.1)
				(type default)
			)
			(layer "F.Fab")
		)
		(fp_line
			(start 0.120396 0.2794)
			(end -0.12065 0.2794)
			(stroke
				(width 0.1)
				(type default)
			)
			(layer "F.Fab")
		)
		(fp_line
			(start 0.120396 0.3048)
			(end 0.120396 0.2794)
			(stroke
				(width 0.1)
				(type default)
			)
			(layer "F.Fab")
		)
		(fp_line
			(start 0.12065 -0.3048)
			(end 0.67945 -0.3048)
			(stroke
				(width 0.1)
				(type default)
			)
			(layer "F.Fab")
		)
		(fp_line
			(start 0.12065 -0.2794)
			(end 0.12065 -0.3048)
			(stroke
				(width 0.1)
				(type default)
			)
			(layer "F.Fab")
		)
		(fp_line
			(start 0.67945 -0.3048)
			(end 0.67945 0.3048)
			(stroke
				(width 0.1)
				(type default)
			)
			(layer "F.Fab")
		)
		(fp_line
			(start 0.67945 0.3048)
			(end 0.120396 0.3048)
			(stroke
				(width 0.1)
				(type default)
			)
			(layer "F.Fab")
		)
		(pad "1" smd rect
			(at -0.40005 0 180)
			(size 0.4572 0.508)
			(layers "F.Cu" "F.Mask" "F.Paste")
			(net "P12V_OCP_V3_2_ISENSE_MAM_TIC")
		)
		(pad "2" smd rect
			(at 0.40005 0 180)
			(size 0.4572 0.508)
			(layers "F.Cu" "F.Mask" "F.Paste")
			(net "P12V_OCP_V3_2_ISENSE_TIC")
		)
	)
	(footprint ""
		(layer "F.Cu")
		(at 428.880016 -102.37724 -90)
		(property "Reference" "R3794"
			(at 0 0 270)
			(layer "F.SilkS")
			(hide yes)
			(effects
				(font
					(size 1.27 1.27)
				)
			)
		)
		(property "Value" ""
			(at 0 0 270)
			(layer "F.Fab")
			(effects
				(font
					(size 1.27 1.27)
				)
			)
		)
		(duplicate_pad_numbers_are_jumpers no)
		(fp_line
			(start -0.7874 0.4064)
			(end -0.7874 -0.4064)
			(stroke
				(width 0.1524)
				(type default)
			)
			(layer "F.SilkS")
		)
		(fp_line
			(start 0.7874 0.4064)
			(end -0.7874 0.4064)
			(stroke
				(width 0.1524)
				(type default)
			)
			(layer "F.SilkS")
		)
		(fp_line
			(start -0.7874 -0.4064)
			(end 0.7874 -0.4064)
			(stroke
				(width 0.1524)
				(type default)
			)
			(layer "F.SilkS")
		)
		(fp_line
			(start 0.7874 -0.4064)
			(end 0.7874 0.4064)
			(stroke
				(width 0.1524)
				(type default)
			)
			(layer "F.SilkS")
		)
		(fp_line
			(start -0.67945 0.3048)
			(end -0.67945 -0.305054)
			(stroke
				(width 0.1)
				(type default)
			)
			(layer "F.Fab")
		)
		(fp_line
			(start -0.12065 0.3048)
			(end -0.67945 0.3048)
			(stroke
				(width 0.1)
				(type default)
			)
			(layer "F.Fab")
		)
		(fp_line
			(start 0.120396 0.3048)
			(end 0.120396 0.2794)
			(stroke
				(width 0.1)
				(type default)
			)
			(layer "F.Fab")
		)
		(fp_line
			(start 0.67945 0.3048)
			(end 0.120396 0.3048)
			(stroke
				(width 0.1)
				(type default)
			)
			(layer "F.Fab")
		)
		(fp_line
			(start -0.12065 0.2794)
			(end -0.12065 0.3048)
			(stroke
				(width 0.1)
				(type default)
			)
			(layer "F.Fab")
		)
		(fp_line
			(start 0.120396 0.2794)
			(end -0.12065 0.2794)
			(stroke
				(width 0.1)
				(type default)
			)
			(layer "F.Fab")
		)
		(fp_line
			(start -0.12065 -0.2794)
			(end 0.12065 -0.2794)
			(stroke
				(width 0.1)
				(type default)
			)
			(layer "F.Fab")
		)
		(fp_line
			(start 0.12065 -0.2794)
			(end 0.12065 -0.3048)
			(stroke
				(width 0.1)
				(type default)
			)
			(layer "F.Fab")
		)
		(fp_line
			(start 0.12065 -0.3048)
			(end 0.67945 -0.3048)
			(stroke
				(width 0.1)
				(type default)
			)
			(layer "F.Fab")
		)
		(fp_line
			(start 0.67945 -0.3048)
			(end 0.67945 0.3048)
			(stroke
				(width 0.1)
				(type default)
			)
			(layer "F.Fab")
		)
		(fp_line
			(start -0.67945 -0.305054)
			(end -0.12065 -0.305054)
			(stroke
				(width 0.1)
				(type default)
			)
			(layer "F.Fab")
		)
		(fp_line
			(start -0.12065 -0.305054)
			(end -0.12065 -0.2794)
			(stroke
				(width 0.1)
				(type default)
			)
			(layer "F.Fab")
		)
		(pad "1" smd circle
			(at -0.40005 0 270)
			(size 0 0)
			(layers "F.Cu" "F.Mask" "F.Paste")
			(net "P3V3_OCP_PWRGD_1")
		)
		(pad "2" smd circle
			(at 0.40005 0 270)
			(size 0 0)
			(layers "F.Cu" "F.Mask" "F.Paste")
			(net "OCP_V3_1_P3V3_PWRGD")
		)
	)
)
